(kicad_pcb
	(version 20260206)
	(generator "pcbnew")
	(generator_version "10.0")
	(general
		(thickness 1.6)
		(legacy_teardrops no)
	)
	(paper "A4")
	(title_block
		(title "04192023_DAF0TMB3IC0_F0TG_MB_C_brd_V02_OCP.brd")
		(comment 1 "Grand Teton / footprints 2724-2730 of 8354")
	)
	(layers
		(0 "F.Cu" signal "TOP")
		(4 "In1.Cu" signal "GND")
		(6 "In2.Cu" signal "IN1")
		(8 "In3.Cu" signal "GND1")
		(10 "In4.Cu" signal "IN2")
		(12 "In5.Cu" signal "GND2")
		(14 "In6.Cu" signal "IN3")
		(16 "In7.Cu" signal "GND3")
		(18 "In8.Cu" signal "VCC")
		(20 "In9.Cu" signal "VCC1")
		(22 "In10.Cu" signal "GND4")
		(24 "In11.Cu" signal "IN4")
		(26 "In12.Cu" signal "GND5")
		(28 "In13.Cu" signal "IN5")
		(30 "In14.Cu" signal "GND6")
		(32 "In15.Cu" signal "IN6")
		(34 "In16.Cu" signal "GND7")
		(2 "B.Cu" signal "BOTTOM")
		(9 "F.Adhes" user "F.Adhesive")
		(11 "B.Adhes" user "B.Adhesive")
		(13 "F.Paste" user "Package Geometry/Pastemask Top")
		(15 "B.Paste" user "Package Geometry/Pastemask Bottom")
		(5 "F.SilkS" user "Ref Des/Silkscreen Top")
		(7 "B.SilkS" user "Ref Des/Silkscreen Bottom")
		(1 "F.Mask" user "Board Geometry/Soldermask Top")
		(3 "B.Mask" user "Board Geometry/Soldermask Bottom")
		(17 "Dwgs.User" user "User.Drawings")
		(19 "Cmts.User" user "User.Comments")
		(21 "Eco1.User" user "User.Eco1")
		(23 "Eco2.User" user "User.Eco2")
		(25 "Edge.Cuts" user "Board Geometry/Outline")
		(27 "Margin" user)
		(31 "F.CrtYd" user "Package Geometry/Place Bound Top")
		(29 "B.CrtYd" user "Package Geometry/Place Bound Bottom")
		(35 "F.Fab" user "Ref Des/Assembly Top")
		(33 "B.Fab" user "Ref Des/Assembly Bottom")
	)
	(footprint ""
		(layer "F.Cu")
		(at 147.16379 -96.012508 90)
		(property "Reference" "C1879"
			(at 0 0 90)
			(layer "F.SilkS")
			(hide yes)
			(effects
				(font
					(size 1.27 1.27)
				)
			)
		)
		(property "Value" ""
			(at 0 0 90)
			(layer "F.Fab")
			(effects
				(font
					(size 1.27 1.27)
				)
			)
		)
		(duplicate_pad_numbers_are_jumpers no)
		(fp_line
			(start 0.7874 -0.4064)
			(end 0.7874 0.4064)
			(stroke
				(width 0.1524)
				(type default)
			)
			(layer "F.SilkS")
		)
		(fp_line
			(start -0.7874 -0.4064)
			(end 0.7874 -0.4064)
			(stroke
				(width 0.1524)
				(type default)
			)
			(layer "F.SilkS")
		)
		(fp_line
			(start 0.7874 0.4064)
			(end -0.7874 0.4064)
			(stroke
				(width 0.1524)
				(type default)
			)
			(layer "F.SilkS")
		)
		(fp_line
			(start -0.7874 0.4064)
			(end -0.7874 -0.4064)
			(stroke
				(width 0.1524)
				(type default)
			)
			(layer "F.SilkS")
		)
		(fp_line
			(start -0.12065 -0.305054)
			(end -0.12065 -0.2794)
			(stroke
				(width 0.1)
				(type default)
			)
			(layer "F.Fab")
		)
		(fp_line
			(start -0.67945 -0.305054)
			(end -0.12065 -0.305054)
			(stroke
				(width 0.1)
				(type default)
			)
			(layer "F.Fab")
		)
		(fp_line
			(start 0.67945 -0.3048)
			(end 0.67945 0.3048)
			(stroke
				(width 0.1)
				(type default)
			)
			(layer "F.Fab")
		)
		(fp_line
			(start 0.12065 -0.3048)
			(end 0.67945 -0.3048)
			(stroke
				(width 0.1)
				(type default)
			)
			(layer "F.Fab")
		)
		(fp_line
			(start 0.12065 -0.2794)
			(end 0.12065 -0.3048)
			(stroke
				(width 0.1)
				(type default)
			)
			(layer "F.Fab")
		)
		(fp_line
			(start -0.12065 -0.2794)
			(end 0.12065 -0.2794)
			(stroke
				(width 0.1)
				(type default)
			)
			(layer "F.Fab")
		)
		(fp_line
			(start 0.120396 0.2794)
			(end -0.12065 0.2794)
			(stroke
				(width 0.1)
				(type default)
			)
			(layer "F.Fab")
		)
		(fp_line
			(start -0.12065 0.2794)
			(end -0.12065 0.3048)
			(stroke
				(width 0.1)
				(type default)
			)
			(layer "F.Fab")
		)
		(fp_line
			(start 0.67945 0.3048)
			(end 0.120396 0.3048)
			(stroke
				(width 0.1)
				(type default)
			)
			(layer "F.Fab")
		)
		(fp_line
			(start 0.120396 0.3048)
			(end 0.120396 0.2794)
			(stroke
				(width 0.1)
				(type default)
			)
			(layer "F.Fab")
		)
		(fp_line
			(start -0.12065 0.3048)
			(end -0.67945 0.3048)
			(stroke
				(width 0.1)
				(type default)
			)
			(layer "F.Fab")
		)
		(fp_line
			(start -0.67945 0.3048)
			(end -0.67945 -0.305054)
			(stroke
				(width 0.1)
				(type default)
			)
			(layer "F.Fab")
		)
		(pad "1" smd circle
			(at -0.40005 0 90)
			(size 0 0)
			(layers "F.Cu" "F.Mask" "F.Paste")
			(net "P3V3_AUX")
		)
		(pad "2" smd circle
			(at 0.40005 0 90)
			(size 0 0)
			(layers "F.Cu" "F.Mask" "F.Paste")
			(net "GND")
		)
	)
	(footprint ""
		(layer "F.Cu")
		(at 131.64058 -26.99258 -90)
		(property "Reference" "R6193"
			(at 0 0 270)
			(layer "F.SilkS")
			(hide yes)
			(effects
				(font
					(size 1.27 1.27)
				)
			)
		)
		(property "Value" ""
			(at 0 0 270)
			(layer "F.Fab")
			(effects
				(font
					(size 1.27 1.27)
				)
			)
		)
		(duplicate_pad_numbers_are_jumpers no)
		(fp_line
			(start -0.32512 0.175006)
			(end -0.32512 -0.175006)
			(stroke
				(width 0.1)
				(type default)
			)
			(layer "F.Fab")
		)
		(fp_line
			(start 0.32512 0.175006)
			(end -0.32512 0.175006)
			(stroke
				(width 0.1)
				(type default)
			)
			(layer "F.Fab")
		)
		(fp_line
			(start -0.32512 -0.175006)
			(end 0.32512 -0.175006)
			(stroke
				(width 0.1)
				(type default)
			)
			(layer "F.Fab")
		)
		(fp_line
			(start 0.32512 -0.175006)
			(end 0.32512 0.175006)
			(stroke
				(width 0.1)
				(type default)
			)
			(layer "F.Fab")
		)
		(pad "1" smd rect
			(at -0.2667 0 270)
			(size 0.3048 0.381)
			(layers "F.Cu" "F.Mask" "F.Paste")
			(net "USB2_CPU0_P0_DN")
		)
		(pad "2" smd rect
			(at 0.2667 0 90)
			(size 0.3048 0.381)
			(layers "F.Cu" "F.Mask" "F.Paste")
			(net "USB2_CPU0_P0_R2_DN")
		)
	)
	(footprint ""
		(layer "F.Cu")
		(at 371.794278 -176.59731)
		(property "Reference" "PC482_2"
			(at 0 0 0)
			(layer "F.SilkS")
			(hide yes)
			(effects
				(font
					(size 1.27 1.27)
				)
			)
		)
		(property "Value" ""
			(at 0 0 0)
			(layer "F.Fab")
			(effects
				(font
					(size 1.27 1.27)
				)
			)
		)
		(duplicate_pad_numbers_are_jumpers no)
		(fp_line
			(start -0.7874 -0.4064)
			(end 0.7874 -0.4064)
			(stroke
				(width 0.1524)
				(type default)
			)
			(layer "F.SilkS")
		)
		(fp_line
			(start -0.7874 0.4064)
			(end -0.7874 -0.4064)
			(stroke
				(width 0.1524)
				(type default)
			)
			(layer "F.SilkS")
		)
		(fp_line
			(start 0.7874 -0.4064)
			(end 0.7874 0.4064)
			(stroke
				(width 0.1524)
				(type default)
			)
			(layer "F.SilkS")
		)
		(fp_line
			(start 0.7874 0.4064)
			(end -0.7874 0.4064)
			(stroke
				(width 0.1524)
				(type default)
			)
			(layer "F.SilkS")
		)
		(fp_line
			(start -0.67945 -0.305054)
			(end -0.12065 -0.305054)
			(stroke
				(width 0.1)
				(type default)
			)
			(layer "F.Fab")
		)
		(fp_line
			(start -0.67945 0.3048)
			(end -0.67945 -0.305054)
			(stroke
				(width 0.1)
				(type default)
			)
			(layer "F.Fab")
		)
		(fp_line
			(start -0.12065 -0.305054)
			(end -0.12065 -0.2794)
			(stroke
				(width 0.1)
				(type default)
			)
			(layer "F.Fab")
		)
		(fp_line
			(start -0.12065 -0.2794)
			(end 0.12065 -0.2794)
			(stroke
				(width 0.1)
				(type default)
			)
			(layer "F.Fab")
		)
		(fp_line
			(start -0.12065 0.2794)
			(end -0.12065 0.3048)
			(stroke
				(width 0.1)
				(type default)
			)
			(layer "F.Fab")
		)
		(fp_line
			(start -0.12065 0.3048)
			(end -0.67945 0.3048)
			(stroke
				(width 0.1)
				(type default)
			)
			(layer "F.Fab")
		)
		(fp_line
			(start 0.120396 0.2794)
			(end -0.12065 0.2794)
			(stroke
				(width 0.1)
				(type default)
			)
			(layer "F.Fab")
		)
		(fp_line
			(start 0.120396 0.3048)
			(end 0.120396 0.2794)
			(stroke
				(width 0.1)
				(type default)
			)
			(layer "F.Fab")
		)
		(fp_line
			(start 0.12065 -0.3048)
			(end 0.67945 -0.3048)
			(stroke
				(width 0.1)
				(type default)
			)
			(layer "F.Fab")
		)
		(fp_line
			(start 0.12065 -0.2794)
			(end 0.12065 -0.3048)
			(stroke
				(width 0.1)
				(type default)
			)
			(layer "F.Fab")
		)
		(fp_line
			(start 0.67945 -0.3048)
			(end 0.67945 0.3048)
			(stroke
				(width 0.1)
				(type default)
			)
			(layer "F.Fab")
		)
		(fp_line
			(start 0.67945 0.3048)
			(end 0.120396 0.3048)
			(stroke
				(width 0.1)
				(type default)
			)
			(layer "F.Fab")
		)
		(pad "1" smd circle
			(at -0.40005 0)
			(size 0 0)
			(layers "F.Cu" "F.Mask" "F.Paste")
			(net "SW_P12V_AUX_PVDDCR_CPU0_P0_FLT")
		)
		(pad "2" smd circle
			(at 0.40005 0)
			(size 0 0)
			(layers "F.Cu" "F.Mask" "F.Paste")
			(net "GND")
		)
	)
	(footprint ""
		(layer "F.Cu")
		(at 352.705416 -438.992772 180)
		(property "Reference" "R4548"
			(at 0 0 180)
			(layer "F.SilkS")
			(hide yes)
			(effects
				(font
					(size 1.27 1.27)
				)
			)
		)
		(property "Value" ""
			(at 0 0 180)
			(layer "F.Fab")
			(effects
				(font
					(size 1.27 1.27)
				)
			)
		)
		(duplicate_pad_numbers_are_jumpers no)
		(fp_line
			(start 0.7874 0.4064)
			(end -0.7874 0.4064)
			(stroke
				(width 0.1524)
				(type default)
			)
			(layer "F.SilkS")
		)
		(fp_line
			(start 0.7874 -0.4064)
			(end 0.7874 0.4064)
			(stroke
				(width 0.1524)
				(type default)
			)
			(layer "F.SilkS")
		)
		(fp_line
			(start -0.7874 0.4064)
			(end -0.7874 -0.4064)
			(stroke
				(width 0.1524)
				(type default)
			)
			(layer "F.SilkS")
		)
		(fp_line
			(start -0.7874 -0.4064)
			(end 0.7874 -0.4064)
			(stroke
				(width 0.1524)
				(type default)
			)
			(layer "F.SilkS")
		)
		(fp_line
			(start 0.67945 0.3048)
			(end 0.120396 0.3048)
			(stroke
				(width 0.1)
				(type default)
			)
			(layer "F.Fab")
		)
		(fp_line
			(start 0.67945 -0.3048)
			(end 0.67945 0.3048)
			(stroke
				(width 0.1)
				(type default)
			)
			(layer "F.Fab")
		)
		(fp_line
			(start 0.12065 -0.2794)
			(end 0.12065 -0.3048)
			(stroke
				(width 0.1)
				(type default)
			)
			(layer "F.Fab")
		)
		(fp_line
			(start 0.12065 -0.3048)
			(end 0.67945 -0.3048)
			(stroke
				(width 0.1)
				(type default)
			)
			(layer "F.Fab")
		)
		(fp_line
			(start 0.120396 0.3048)
			(end 0.120396 0.2794)
			(stroke
				(width 0.1)
				(type default)
			)
			(layer "F.Fab")
		)
		(fp_line
			(start 0.120396 0.2794)
			(end -0.12065 0.2794)
			(stroke
				(width 0.1)
				(type default)
			)
			(layer "F.Fab")
		)
		(fp_line
			(start -0.12065 0.3048)
			(end -0.67945 0.3048)
			(stroke
				(width 0.1)
				(type default)
			)
			(layer "F.Fab")
		)
		(fp_line
			(start -0.12065 0.2794)
			(end -0.12065 0.3048)
			(stroke
				(width 0.1)
				(type default)
			)
			(layer "F.Fab")
		)
		(fp_line
			(start -0.12065 -0.2794)
			(end 0.12065 -0.2794)
			(stroke
				(width 0.1)
				(type default)
			)
			(layer "F.Fab")
		)
		(fp_line
			(start -0.12065 -0.305054)
			(end -0.12065 -0.2794)
			(stroke
				(width 0.1)
				(type default)
			)
			(layer "F.Fab")
		)
		(fp_line
			(start -0.67945 0.3048)
			(end -0.67945 -0.305054)
			(stroke
				(width 0.1)
				(type default)
			)
			(layer "F.Fab")
		)
		(fp_line
			(start -0.67945 -0.305054)
			(end -0.12065 -0.305054)
			(stroke
				(width 0.1)
				(type default)
			)
			(layer "F.Fab")
		)
		(pad "1" smd circle
			(at -0.40005 0 180)
			(size 0 0)
			(layers "F.Cu" "F.Mask" "F.Paste")
			(net "SWB_HSC_EN")
		)
		(pad "2" smd circle
			(at 0.40005 0 180)
			(size 0 0)
			(layers "F.Cu" "F.Mask" "F.Paste")
			(net "GND")
		)
	)
	(footprint ""
		(layer "F.Cu")
		(at 397.369538 -392.1252)
		(property "Reference" "R1077"
			(at 0 0 0)
			(layer "F.SilkS")
			(hide yes)
			(effects
				(font
					(size 1.27 1.27)
				)
			)
		)
		(property "Value" ""
			(at 0 0 0)
			(layer "F.Fab")
			(effects
				(font
					(size 1.27 1.27)
				)
			)
		)
		(duplicate_pad_numbers_are_jumpers no)
		(fp_line
			(start -0.32512 -0.175006)
			(end 0.32512 -0.175006)
			(stroke
				(width 0.1)
				(type default)
			)
			(layer "F.Fab")
		)
		(fp_line
			(start -0.32512 0.175006)
			(end -0.32512 -0.175006)
			(stroke
				(width 0.1)
				(type default)
			)
			(layer "F.Fab")
		)
		(fp_line
			(start 0.32512 -0.175006)
			(end 0.32512 0.175006)
			(stroke
				(width 0.1)
				(type default)
			)
			(layer "F.Fab")
		)
		(fp_line
			(start 0.32512 0.175006)
			(end -0.32512 0.175006)
			(stroke
				(width 0.1)
				(type default)
			)
			(layer "F.Fab")
		)
		(pad "1" smd rect
			(at -0.2667 0)
			(size 0.3048 0.381)
			(layers "F.Cu" "F.Mask" "F.Paste")
			(net "P1V8_CPU0_RT_1D")
		)
		(pad "2" smd rect
			(at 0.2667 0 180)
			(size 0.3048 0.381)
			(layers "F.Cu" "F.Mask" "F.Paste")
			(net "TEST2_RT_CPU0_P2")
		)
	)
	(footprint ""
		(layer "F.Cu")
		(at 423.631868 -360.824018)
		(property "Reference" "PR126"
			(at 0 0 0)
			(layer "F.SilkS")
			(hide yes)
			(effects
				(font
					(size 1.27 1.27)
				)
			)
		)
		(property "Value" ""
			(at 0 0 0)
			(layer "F.Fab")
			(effects
				(font
					(size 1.27 1.27)
				)
			)
		)
		(duplicate_pad_numbers_are_jumpers no)
		(fp_line
			(start -0.7874 -0.4064)
			(end 0.7874 -0.4064)
			(stroke
				(width 0.1524)
				(type default)
			)
			(layer "F.SilkS")
		)
		(fp_line
			(start -0.7874 0.4064)
			(end -0.7874 -0.4064)
			(stroke
				(width 0.1524)
				(type default)
			)
			(layer "F.SilkS")
		)
		(fp_line
			(start 0.7874 -0.4064)
			(end 0.7874 0.4064)
			(stroke
				(width 0.1524)
				(type default)
			)
			(layer "F.SilkS")
		)
		(fp_line
			(start 0.7874 0.4064)
			(end -0.7874 0.4064)
			(stroke
				(width 0.1524)
				(type default)
			)
			(layer "F.SilkS")
		)
		(fp_line
			(start -0.67945 -0.305054)
			(end -0.12065 -0.305054)
			(stroke
				(width 0.1)
				(type default)
			)
			(layer "F.Fab")
		)
		(fp_line
			(start -0.67945 0.3048)
			(end -0.67945 -0.305054)
			(stroke
				(width 0.1)
				(type default)
			)
			(layer "F.Fab")
		)
		(fp_line
			(start -0.12065 -0.305054)
			(end -0.12065 -0.2794)
			(stroke
				(width 0.1)
				(type default)
			)
			(layer "F.Fab")
		)
		(fp_line
			(start -0.12065 -0.2794)
			(end 0.12065 -0.2794)
			(stroke
				(width 0.1)
				(type default)
			)
			(layer "F.Fab")
		)
		(fp_line
			(start -0.12065 0.2794)
			(end -0.12065 0.3048)
			(stroke
				(width 0.1)
				(type default)
			)
			(layer "F.Fab")
		)
		(fp_line
			(start -0.12065 0.3048)
			(end -0.67945 0.3048)
			(stroke
				(width 0.1)
				(type default)
			)
			(layer "F.Fab")
		)
		(fp_line
			(start 0.120396 0.2794)
			(end -0.12065 0.2794)
			(stroke
				(width 0.1)
				(type default)
			)
			(layer "F.Fab")
		)
		(fp_line
			(start 0.120396 0.3048)
			(end 0.120396 0.2794)
			(stroke
				(width 0.1)
				(type default)
			)
			(layer "F.Fab")
		)
		(fp_line
			(start 0.12065 -0.3048)
			(end 0.67945 -0.3048)
			(stroke
				(width 0.1)
				(type default)
			)
			(layer "F.Fab")
		)
		(fp_line
			(start 0.12065 -0.2794)
			(end 0.12065 -0.3048)
			(stroke
				(width 0.1)
				(type default)
			)
			(layer "F.Fab")
		)
		(fp_line
			(start 0.67945 -0.3048)
			(end 0.67945 0.3048)
			(stroke
				(width 0.1)
				(type default)
			)
			(layer "F.Fab")
		)
		(fp_line
			(start 0.67945 0.3048)
			(end 0.120396 0.3048)
			(stroke
				(width 0.1)
				(type default)
			)
			(layer "F.Fab")
		)
		(pad "1" smd circle
			(at -0.40005 0)
			(size 0 0)
			(layers "F.Cu" "F.Mask" "F.Paste")
			(net "PVDD11_S3_P0_ADDR_CFG")
		)
		(pad "2" smd circle
			(at 0.40005 0)
			(size 0 0)
			(layers "F.Cu" "F.Mask" "F.Paste")
			(net "GND")
		)
	)
	(footprint ""
		(layer "F.Cu")
		(at 215.585548 -133.600952 90)
		(property "Reference" "C345"
			(at 0 0 90)
			(layer "F.SilkS")
			(hide yes)
			(effects
				(font
					(size 1.27 1.27)
				)
			)
		)
		(property "Value" ""
			(at 0 0 90)
			(layer "F.Fab")
			(effects
				(font
					(size 1.27 1.27)
				)
			)
		)
		(duplicate_pad_numbers_are_jumpers no)
		(fp_line
			(start 0.7874 -0.4064)
			(end 0.7874 0.4064)
			(stroke
				(width 0.1524)
				(type default)
			)
			(layer "F.SilkS")
		)
		(fp_line
			(start -0.7874 -0.4064)
			(end 0.7874 -0.4064)
			(stroke
				(width 0.1524)
				(type default)
			)
			(layer "F.SilkS")
		)
		(fp_line
			(start 0.7874 0.4064)
			(end -0.7874 0.4064)
			(stroke
				(width 0.1524)
				(type default)
			)
			(layer "F.SilkS")
		)
		(fp_line
			(start -0.7874 0.4064)
			(end -0.7874 -0.4064)
			(stroke
				(width 0.1524)
				(type default)
			)
			(layer "F.SilkS")
		)
		(fp_line
			(start -0.12065 -0.305054)
			(end -0.12065 -0.2794)
			(stroke
				(width 0.1)
				(type default)
			)
			(layer "F.Fab")
		)
		(fp_line
			(start -0.67945 -0.305054)
			(end -0.12065 -0.305054)
			(stroke
				(width 0.1)
				(type default)
			)
			(layer "F.Fab")
		)
		(fp_line
			(start 0.67945 -0.3048)
			(end 0.67945 0.3048)
			(stroke
				(width 0.1)
				(type default)
			)
			(layer "F.Fab")
		)
		(fp_line
			(start 0.12065 -0.3048)
			(end 0.67945 -0.3048)
			(stroke
				(width 0.1)
				(type default)
			)
			(layer "F.Fab")
		)
		(fp_line
			(start 0.12065 -0.2794)
			(end 0.12065 -0.3048)
			(stroke
				(width 0.1)
				(type default)
			)
			(layer "F.Fab")
		)
		(fp_line
			(start -0.12065 -0.2794)
			(end 0.12065 -0.2794)
			(stroke
				(width 0.1)
				(type default)
			)
			(layer "F.Fab")
		)
		(fp_line
			(start 0.120396 0.2794)
			(end -0.12065 0.2794)
			(stroke
				(width 0.1)
				(type default)
			)
			(layer "F.Fab")
		)
		(fp_line
			(start -0.12065 0.2794)
			(end -0.12065 0.3048)
			(stroke
				(width 0.1)
				(type default)
			)
			(layer "F.Fab")
		)
		(fp_line
			(start 0.67945 0.3048)
			(end 0.120396 0.3048)
			(stroke
				(width 0.1)
				(type default)
			)
			(layer "F.Fab")
		)
		(fp_line
			(start 0.120396 0.3048)
			(end 0.120396 0.2794)
			(stroke
				(width 0.1)
				(type default)
			)
			(layer "F.Fab")
		)
		(fp_line
			(start -0.12065 0.3048)
			(end -0.67945 0.3048)
			(stroke
				(width 0.1)
				(type default)
			)
			(layer "F.Fab")
		)
		(fp_line
			(start -0.67945 0.3048)
			(end -0.67945 -0.305054)
			(stroke
				(width 0.1)
				(type default)
			)
			(layer "F.Fab")
		)
		(pad "1" smd circle
			(at -0.40005 0 90)
			(size 0 0)
			(layers "F.Cu" "F.Mask" "F.Paste")
			(net "P1V8_AUX_ENABLE")
		)
		(pad "2" smd circle
			(at 0.40005 0 90)
			(size 0 0)
			(layers "F.Cu" "F.Mask" "F.Paste")
			(net "GND")
		)
	)
)
